(kicad_pcb
	(version 20260206)
	(generator "pcbnew")
	(generator_version "10.0")
	(general
		(thickness 1.6)
		(legacy_teardrops no)
	)
	(paper "A4")
	(title_block
		(title "9054_F0T_PDB_BD_GPU_F_V04_1213_1550_OCP.brd")
		(comment 1 "Grand Teton / footprints 204-210 of 608")
	)
	(layers
		(0 "F.Cu" signal "TOP")
		(4 "In1.Cu" signal "GND")
		(6 "In2.Cu" signal "IN1")
		(8 "In3.Cu" signal "GND1")
		(10 "In4.Cu" signal "VCC")
		(12 "In5.Cu" signal "VCC1")
		(14 "In6.Cu" signal "GND2")
		(16 "In7.Cu" signal "IN2")
		(18 "In8.Cu" signal "GND3")
		(2 "B.Cu" signal "BOTTOM")
		(9 "F.Adhes" user "F.Adhesive")
		(11 "B.Adhes" user "B.Adhesive")
		(13 "F.Paste" user "Package Geometry/Pastemask Top")
		(15 "B.Paste" user "Package Geometry/Pastemask Bottom")
		(5 "F.SilkS" user "Ref Des/Silkscreen Top")
		(7 "B.SilkS" user "Ref Des/Silkscreen Bottom")
		(1 "F.Mask" user "Board Geometry/Soldermask Top")
		(3 "B.Mask" user "Board Geometry/Soldermask Bottom")
		(17 "Dwgs.User" user "User.Drawings")
		(19 "Cmts.User" user "User.Comments")
		(21 "Eco1.User" user "User.Eco1")
		(23 "Eco2.User" user "User.Eco2")
		(25 "Edge.Cuts" user "Board Geometry/Outline")
		(27 "Margin" user)
		(31 "F.CrtYd" user "Package Geometry/Place Bound Top")
		(29 "B.CrtYd" user "Package Geometry/Place Bound Bottom")
		(35 "F.Fab" user "Ref Des/Assembly Top")
		(33 "B.Fab" user "Ref Des/Assembly Bottom")
	)
	(footprint ""
		(layer "F.Cu")
		(at 431.8 -137.500106 180)
		(property "Reference" "H20"
			(at -1.8415 -6.094476 0)
			(unlocked yes)
			(layer "F.SilkS")
			(effects
				(font
					(size 0.7874 0.5842)
					(thickness 0.1524)
				)
				(justify left)
			)
		)
		(property "Value" ""
			(at 0 0 180)
			(layer "F.Fab")
			(effects
				(font
					(size 1.27 1.27)
				)
			)
		)
		(duplicate_pad_numbers_are_jumpers no)
		(pad "1" thru_hole circle
			(at 0 0 180)
			(size 10.16 10.16)
			(drill 6.4008
				(offset 0 0)
			)
			(layers "*.Cu" "*.Mask")
			(remove_unused_layers no)
			(net "GND")
			(clearance -1.6256)
			(padstack
				(mode front_inner_back)
				(layer "Inner"
					(shape circle)
					(size 10.16 10.16)
					(clearance -1.6256)
				)
				(layer "B.Cu"
					(shape oval)
					(size 10.0076 17.018)
					(offset 0 3.499866)
					(clearance -1.5494)
				)
			)
		)
	)
	(footprint ""
		(layer "F.Cu")
		(at 165.989 -83.439 90)
		(property "Reference" "C106"
			(at 0 0 90)
			(layer "F.SilkS")
			(hide yes)
			(effects
				(font
					(size 1.27 1.27)
				)
			)
		)
		(property "Value" ""
			(at 0 0 90)
			(layer "F.Fab")
			(effects
				(font
					(size 1.27 1.27)
				)
			)
		)
		(duplicate_pad_numbers_are_jumpers no)
		(fp_line
			(start 0.7874 -0.4064)
			(end 0.7874 0.4064)
			(stroke
				(width 0.1524)
				(type default)
			)
			(layer "F.SilkS")
		)
		(fp_line
			(start -0.7874 -0.4064)
			(end 0.7874 -0.4064)
			(stroke
				(width 0.1524)
				(type default)
			)
			(layer "F.SilkS")
		)
		(fp_line
			(start 0.7874 0.4064)
			(end -0.7874 0.4064)
			(stroke
				(width 0.1524)
				(type default)
			)
			(layer "F.SilkS")
		)
		(fp_line
			(start -0.7874 0.4064)
			(end -0.7874 -0.4064)
			(stroke
				(width 0.1524)
				(type default)
			)
			(layer "F.SilkS")
		)
		(fp_line
			(start -0.12065 -0.305054)
			(end -0.12065 -0.2794)
			(stroke
				(width 0.1)
				(type default)
			)
			(layer "F.Fab")
		)
		(fp_line
			(start -0.67945 -0.305054)
			(end -0.12065 -0.305054)
			(stroke
				(width 0.1)
				(type default)
			)
			(layer "F.Fab")
		)
		(fp_line
			(start 0.67945 -0.3048)
			(end 0.67945 0.3048)
			(stroke
				(width 0.1)
				(type default)
			)
			(layer "F.Fab")
		)
		(fp_line
			(start 0.12065 -0.3048)
			(end 0.67945 -0.3048)
			(stroke
				(width 0.1)
				(type default)
			)
			(layer "F.Fab")
		)
		(fp_line
			(start 0.12065 -0.2794)
			(end 0.12065 -0.3048)
			(stroke
				(width 0.1)
				(type default)
			)
			(layer "F.Fab")
		)
		(fp_line
			(start -0.12065 -0.2794)
			(end 0.12065 -0.2794)
			(stroke
				(width 0.1)
				(type default)
			)
			(layer "F.Fab")
		)
		(fp_line
			(start 0.120396 0.2794)
			(end -0.12065 0.2794)
			(stroke
				(width 0.1)
				(type default)
			)
			(layer "F.Fab")
		)
		(fp_line
			(start -0.12065 0.2794)
			(end -0.12065 0.3048)
			(stroke
				(width 0.1)
				(type default)
			)
			(layer "F.Fab")
		)
		(fp_line
			(start 0.67945 0.3048)
			(end 0.120396 0.3048)
			(stroke
				(width 0.1)
				(type default)
			)
			(layer "F.Fab")
		)
		(fp_line
			(start 0.120396 0.3048)
			(end 0.120396 0.2794)
			(stroke
				(width 0.1)
				(type default)
			)
			(layer "F.Fab")
		)
		(fp_line
			(start -0.12065 0.3048)
			(end -0.67945 0.3048)
			(stroke
				(width 0.1)
				(type default)
			)
			(layer "F.Fab")
		)
		(fp_line
			(start -0.67945 0.3048)
			(end -0.67945 -0.305054)
			(stroke
				(width 0.1)
				(type default)
			)
			(layer "F.Fab")
		)
		(pad "1" smd circle
			(at -0.40005 0 90)
			(size 0 0)
			(layers "F.Cu" "F.Mask" "F.Paste")
			(net "GND")
		)
		(pad "2" smd circle
			(at 0.40005 0 90)
			(size 0 0)
			(layers "F.Cu" "F.Mask" "F.Paste")
			(net "P3V3_AUX")
		)
	)
	(footprint ""
		(layer "F.Cu")
		(at 452.073264 -85.870796 -90)
		(property "Reference" "PC54"
			(at 0 0 270)
			(layer "F.SilkS")
			(hide yes)
			(effects
				(font
					(size 1.27 1.27)
				)
			)
		)
		(property "Value" ""
			(at 0 0 270)
			(layer "F.Fab")
			(effects
				(font
					(size 1.27 1.27)
				)
			)
		)
		(duplicate_pad_numbers_are_jumpers no)
		(fp_line
			(start -0.7874 0.4064)
			(end -0.7874 -0.4064)
			(stroke
				(width 0.1524)
				(type default)
			)
			(layer "F.SilkS")
		)
		(fp_line
			(start 0.7874 0.4064)
			(end -0.7874 0.4064)
			(stroke
				(width 0.1524)
				(type default)
			)
			(layer "F.SilkS")
		)
		(fp_line
			(start -0.7874 -0.4064)
			(end 0.7874 -0.4064)
			(stroke
				(width 0.1524)
				(type default)
			)
			(layer "F.SilkS")
		)
		(fp_line
			(start 0.7874 -0.4064)
			(end 0.7874 0.4064)
			(stroke
				(width 0.1524)
				(type default)
			)
			(layer "F.SilkS")
		)
		(fp_line
			(start -0.67945 0.3048)
			(end -0.67945 -0.305054)
			(stroke
				(width 0.1)
				(type default)
			)
			(layer "F.Fab")
		)
		(fp_line
			(start -0.12065 0.3048)
			(end -0.67945 0.3048)
			(stroke
				(width 0.1)
				(type default)
			)
			(layer "F.Fab")
		)
		(fp_line
			(start 0.120396 0.3048)
			(end 0.120396 0.2794)
			(stroke
				(width 0.1)
				(type default)
			)
			(layer "F.Fab")
		)
		(fp_line
			(start 0.67945 0.3048)
			(end 0.120396 0.3048)
			(stroke
				(width 0.1)
				(type default)
			)
			(layer "F.Fab")
		)
		(fp_line
			(start -0.12065 0.2794)
			(end -0.12065 0.3048)
			(stroke
				(width 0.1)
				(type default)
			)
			(layer "F.Fab")
		)
		(fp_line
			(start 0.120396 0.2794)
			(end -0.12065 0.2794)
			(stroke
				(width 0.1)
				(type default)
			)
			(layer "F.Fab")
		)
		(fp_line
			(start -0.12065 -0.2794)
			(end 0.12065 -0.2794)
			(stroke
				(width 0.1)
				(type default)
			)
			(layer "F.Fab")
		)
		(fp_line
			(start 0.12065 -0.2794)
			(end 0.12065 -0.3048)
			(stroke
				(width 0.1)
				(type default)
			)
			(layer "F.Fab")
		)
		(fp_line
			(start 0.12065 -0.3048)
			(end 0.67945 -0.3048)
			(stroke
				(width 0.1)
				(type default)
			)
			(layer "F.Fab")
		)
		(fp_line
			(start 0.67945 -0.3048)
			(end 0.67945 0.3048)
			(stroke
				(width 0.1)
				(type default)
			)
			(layer "F.Fab")
		)
		(fp_line
			(start -0.67945 -0.305054)
			(end -0.12065 -0.305054)
			(stroke
				(width 0.1)
				(type default)
			)
			(layer "F.Fab")
		)
		(fp_line
			(start -0.12065 -0.305054)
			(end -0.12065 -0.2794)
			(stroke
				(width 0.1)
				(type default)
			)
			(layer "F.Fab")
		)
		(pad "1" smd circle
			(at -0.40005 0 270)
			(size 0 0)
			(layers "F.Cu" "F.Mask" "F.Paste")
			(net "P3V3_HPDB_FB")
		)
		(pad "2" smd circle
			(at 0.40005 0 270)
			(size 0 0)
			(layers "F.Cu" "F.Mask" "F.Paste")
			(net "P3V3_AUX")
		)
	)
	(footprint ""
		(layer "F.Cu")
		(at 283.6164 -75.184)
		(property "Reference" "PC12"
			(at 0 0 0)
			(layer "F.SilkS")
			(hide yes)
			(effects
				(font
					(size 1.27 1.27)
				)
			)
		)
		(property "Value" ""
			(at 0 0 0)
			(layer "F.Fab")
			(effects
				(font
					(size 1.27 1.27)
				)
			)
		)
		(duplicate_pad_numbers_are_jumpers no)
		(fp_line
			(start -0.7874 -0.4064)
			(end 0.7874 -0.4064)
			(stroke
				(width 0.1524)
				(type default)
			)
			(layer "F.SilkS")
		)
		(fp_line
			(start -0.7874 0.4064)
			(end -0.7874 -0.4064)
			(stroke
				(width 0.1524)
				(type default)
			)
			(layer "F.SilkS")
		)
		(fp_line
			(start 0.7874 -0.4064)
			(end 0.7874 0.4064)
			(stroke
				(width 0.1524)
				(type default)
			)
			(layer "F.SilkS")
		)
		(fp_line
			(start 0.7874 0.4064)
			(end -0.7874 0.4064)
			(stroke
				(width 0.1524)
				(type default)
			)
			(layer "F.SilkS")
		)
		(fp_line
			(start -0.67945 -0.305054)
			(end -0.12065 -0.305054)
			(stroke
				(width 0.1)
				(type default)
			)
			(layer "F.Fab")
		)
		(fp_line
			(start -0.67945 0.3048)
			(end -0.67945 -0.305054)
			(stroke
				(width 0.1)
				(type default)
			)
			(layer "F.Fab")
		)
		(fp_line
			(start -0.12065 -0.305054)
			(end -0.12065 -0.2794)
			(stroke
				(width 0.1)
				(type default)
			)
			(layer "F.Fab")
		)
		(fp_line
			(start -0.12065 -0.2794)
			(end 0.12065 -0.2794)
			(stroke
				(width 0.1)
				(type default)
			)
			(layer "F.Fab")
		)
		(fp_line
			(start -0.12065 0.2794)
			(end -0.12065 0.3048)
			(stroke
				(width 0.1)
				(type default)
			)
			(layer "F.Fab")
		)
		(fp_line
			(start -0.12065 0.3048)
			(end -0.67945 0.3048)
			(stroke
				(width 0.1)
				(type default)
			)
			(layer "F.Fab")
		)
		(fp_line
			(start 0.120396 0.2794)
			(end -0.12065 0.2794)
			(stroke
				(width 0.1)
				(type default)
			)
			(layer "F.Fab")
		)
		(fp_line
			(start 0.120396 0.3048)
			(end 0.120396 0.2794)
			(stroke
				(width 0.1)
				(type default)
			)
			(layer "F.Fab")
		)
		(fp_line
			(start 0.12065 -0.3048)
			(end 0.67945 -0.3048)
			(stroke
				(width 0.1)
				(type default)
			)
			(layer "F.Fab")
		)
		(fp_line
			(start 0.12065 -0.2794)
			(end 0.12065 -0.3048)
			(stroke
				(width 0.1)
				(type default)
			)
			(layer "F.Fab")
		)
		(fp_line
			(start 0.67945 -0.3048)
			(end 0.67945 0.3048)
			(stroke
				(width 0.1)
				(type default)
			)
			(layer "F.Fab")
		)
		(fp_line
			(start 0.67945 0.3048)
			(end 0.120396 0.3048)
			(stroke
				(width 0.1)
				(type default)
			)
			(layer "F.Fab")
		)
		(pad "1" smd circle
			(at -0.40005 0)
			(size 0 0)
			(layers "F.Cu" "F.Mask" "F.Paste")
			(net "P52V_HS1_EFAULT")
		)
		(pad "2" smd circle
			(at 0.40005 0)
			(size 0 0)
			(layers "F.Cu" "F.Mask" "F.Paste")
			(net "GND_FIELD_SIGNAL")
		)
	)
	(footprint ""
		(layer "F.Cu")
		(at 409.956 -43.942)
		(property "Reference" "R51"
			(at 0 0 0)
			(layer "F.SilkS")
			(hide yes)
			(effects
				(font
					(size 1.27 1.27)
				)
			)
		)
		(property "Value" ""
			(at 0 0 0)
			(layer "F.Fab")
			(effects
				(font
					(size 1.27 1.27)
				)
			)
		)
		(duplicate_pad_numbers_are_jumpers no)
		(fp_line
			(start -0.7874 -0.4064)
			(end 0.7874 -0.4064)
			(stroke
				(width 0.1524)
				(type default)
			)
			(layer "F.SilkS")
		)
		(fp_line
			(start -0.7874 0.4064)
			(end -0.7874 -0.4064)
			(stroke
				(width 0.1524)
				(type default)
			)
			(layer "F.SilkS")
		)
		(fp_line
			(start 0.7874 -0.4064)
			(end 0.7874 0.4064)
			(stroke
				(width 0.1524)
				(type default)
			)
			(layer "F.SilkS")
		)
		(fp_line
			(start 0.7874 0.4064)
			(end -0.7874 0.4064)
			(stroke
				(width 0.1524)
				(type default)
			)
			(layer "F.SilkS")
		)
		(fp_line
			(start -0.67945 -0.305054)
			(end -0.12065 -0.305054)
			(stroke
				(width 0.1)
				(type default)
			)
			(layer "F.Fab")
		)
		(fp_line
			(start -0.67945 0.3048)
			(end -0.67945 -0.305054)
			(stroke
				(width 0.1)
				(type default)
			)
			(layer "F.Fab")
		)
		(fp_line
			(start -0.12065 -0.305054)
			(end -0.12065 -0.2794)
			(stroke
				(width 0.1)
				(type default)
			)
			(layer "F.Fab")
		)
		(fp_line
			(start -0.12065 -0.2794)
			(end 0.12065 -0.2794)
			(stroke
				(width 0.1)
				(type default)
			)
			(layer "F.Fab")
		)
		(fp_line
			(start -0.12065 0.2794)
			(end -0.12065 0.3048)
			(stroke
				(width 0.1)
				(type default)
			)
			(layer "F.Fab")
		)
		(fp_line
			(start -0.12065 0.3048)
			(end -0.67945 0.3048)
			(stroke
				(width 0.1)
				(type default)
			)
			(layer "F.Fab")
		)
		(fp_line
			(start 0.120396 0.2794)
			(end -0.12065 0.2794)
			(stroke
				(width 0.1)
				(type default)
			)
			(layer "F.Fab")
		)
		(fp_line
			(start 0.120396 0.3048)
			(end 0.120396 0.2794)
			(stroke
				(width 0.1)
				(type default)
			)
			(layer "F.Fab")
		)
		(fp_line
			(start 0.12065 -0.3048)
			(end 0.67945 -0.3048)
			(stroke
				(width 0.1)
				(type default)
			)
			(layer "F.Fab")
		)
		(fp_line
			(start 0.12065 -0.2794)
			(end 0.12065 -0.3048)
			(stroke
				(width 0.1)
				(type default)
			)
			(layer "F.Fab")
		)
		(fp_line
			(start 0.67945 -0.3048)
			(end 0.67945 0.3048)
			(stroke
				(width 0.1)
				(type default)
			)
			(layer "F.Fab")
		)
		(fp_line
			(start 0.67945 0.3048)
			(end 0.120396 0.3048)
			(stroke
				(width 0.1)
				(type default)
			)
			(layer "F.Fab")
		)
		(pad "1" smd circle
			(at -0.40005 0)
			(size 0 0)
			(layers "F.Cu" "F.Mask" "F.Paste")
			(net "P3V3_AUX")
		)
		(pad "2" smd circle
			(at 0.40005 0)
			(size 0 0)
			(layers "F.Cu" "F.Mask" "F.Paste")
			(net "PCA9555_A2")
		)
	)
	(footprint ""
		(layer "F.Cu")
		(at 443.5094 -62.103 -90)
		(property "Reference" "PC137"
			(at 4.61137 2.7813 0)
			(unlocked yes)
			(layer "F.SilkS")
			(effects
				(font
					(size 0.7874 0.5842)
					(thickness 0.1524)
				)
				(justify left)
			)
		)
		(property "Value" ""
			(at 0 0 270)
			(layer "F.Fab")
			(effects
				(font
					(size 1.27 1.27)
				)
			)
		)
		(duplicate_pad_numbers_are_jumpers no)
		(fp_line
			(start -1.988058 2.750058)
			(end 2.750058 2.750058)
			(stroke
				(width 0.1524)
				(type default)
			)
			(layer "F.SilkS")
		)
		(fp_line
			(start 2.750058 2.750058)
			(end 2.750058 0.9398)
			(stroke
				(width 0.1524)
				(type default)
			)
			(layer "F.SilkS")
		)
		(fp_line
			(start -2.750058 1.988058)
			(end -1.988058 2.750058)
			(stroke
				(width 0.1524)
				(type default)
			)
			(layer "F.SilkS")
		)
		(fp_line
			(start -2.750058 0.9398)
			(end -2.750058 1.988058)
			(stroke
				(width 0.1524)
				(type default)
			)
			(layer "F.SilkS")
		)
		(fp_line
			(start 2.750058 -0.9398)
			(end 2.750058 -2.750058)
			(stroke
				(width 0.1524)
				(type default)
			)
			(layer "F.SilkS")
		)
		(fp_line
			(start -2.750058 -1.988058)
			(end -2.750058 -0.9398)
			(stroke
				(width 0.1524)
				(type default)
			)
			(layer "F.SilkS")
		)
		(fp_line
			(start -1.988058 -2.750058)
			(end -2.750058 -1.988058)
			(stroke
				(width 0.1524)
				(type default)
			)
			(layer "F.SilkS")
		)
		(fp_line
			(start 2.750058 -2.750058)
			(end -1.988058 -2.750058)
			(stroke
				(width 0.1524)
				(type default)
			)
			(layer "F.SilkS")
		)
		(fp_line
			(start -2.750058 2.750058)
			(end 2.750058 2.750058)
			(stroke
				(width 0.1)
				(type default)
			)
			(layer "F.Fab")
		)
		(fp_line
			(start 2.750058 2.750058)
			(end 2.750058 -2.750058)
			(stroke
				(width 0.1)
				(type default)
			)
			(layer "F.Fab")
		)
		(fp_line
			(start -2.750058 -2.750058)
			(end -2.750058 2.750058)
			(stroke
				(width 0.1)
				(type default)
			)
			(layer "F.Fab")
		)
		(fp_line
			(start 2.750058 -2.750058)
			(end -2.750058 -2.750058)
			(stroke
				(width 0.1)
				(type default)
			)
			(layer "F.Fab")
		)
		(pad "1" smd rect
			(at -2.199894 0)
			(size 1.6002 3.0226)
			(layers "F.Cu" "F.Mask" "F.Paste")
			(net "P3V3_AUX")
		)
		(pad "2" smd rect
			(at 2.199894 0)
			(size 1.6002 3.0226)
			(layers "F.Cu" "F.Mask" "F.Paste")
			(net "GND")
		)
	)
	(footprint ""
		(layer "F.Cu")
		(at 414.49244 -24.36622)
		(property "Reference" "R5920"
			(at 0 0 0)
			(layer "F.SilkS")
			(hide yes)
			(effects
				(font
					(size 1.27 1.27)
				)
			)
		)
		(property "Value" ""
			(at 0 0 0)
			(layer "F.Fab")
			(effects
				(font
					(size 1.27 1.27)
				)
			)
		)
		(duplicate_pad_numbers_are_jumpers no)
		(fp_line
			(start -1.2954 -0.5842)
			(end 1.2954 -0.5842)
			(stroke
				(width 0.1524)
				(type default)
			)
			(layer "F.SilkS")
		)
		(fp_line
			(start -1.2954 0.5842)
			(end -1.2954 -0.5842)
			(stroke
				(width 0.1524)
				(type default)
			)
			(layer "F.SilkS")
		)
		(fp_line
			(start 1.2954 -0.5842)
			(end 1.2954 0.5842)
			(stroke
				(width 0.1524)
				(type default)
			)
			(layer "F.SilkS")
		)
		(fp_line
			(start 1.2954 0.5842)
			(end -1.2954 0.5842)
			(stroke
				(width 0.1524)
				(type default)
			)
			(layer "F.SilkS")
		)
		(fp_line
			(start -1.1938 -0.406654)
			(end -0.8636 -0.406654)
			(stroke
				(width 0.1)
				(type default)
			)
			(layer "F.Fab")
		)
		(fp_line
			(start -1.1938 0.4064)
			(end -1.1938 -0.406654)
			(stroke
				(width 0.1)
				(type default)
			)
			(layer "F.Fab")
		)
		(fp_line
			(start -0.8636 -0.4572)
			(end 0.8636 -0.4572)
			(stroke
				(width 0.1)
				(type default)
			)
			(layer "F.Fab")
		)
		(fp_line
			(start -0.8636 -0.406654)
			(end -0.8636 -0.4572)
			(stroke
				(width 0.1)
				(type default)
			)
			(layer "F.Fab")
		)
		(fp_line
			(start -0.8636 0.4064)
			(end -1.1938 0.4064)
			(stroke
				(width 0.1)
				(type default)
			)
			(layer "F.Fab")
		)
		(fp_line
			(start -0.8636 0.4318)
			(end -0.8636 0.4064)
			(stroke
				(width 0.1)
				(type default)
			)
			(layer "F.Fab")
		)
		(fp_line
			(start -0.8636 0.4572)
			(end -0.8636 0.4318)
			(stroke
				(width 0.1)
				(type default)
			)
			(layer "F.Fab")
		)
		(fp_line
			(start 0.8636 -0.4572)
			(end 0.8636 -0.406654)
			(stroke
				(width 0.1)
				(type default)
			)
			(layer "F.Fab")
		)
		(fp_line
			(start 0.8636 -0.406654)
			(end 1.1938 -0.406654)
			(stroke
				(width 0.1)
				(type default)
			)
			(layer "F.Fab")
		)
		(fp_line
			(start 0.8636 0.4064)
			(end 0.8636 0.4572)
			(stroke
				(width 0.1)
				(type default)
			)
			(layer "F.Fab")
		)
		(fp_line
			(start 0.8636 0.4572)
			(end -0.8636 0.4572)
			(stroke
				(width 0.1)
				(type default)
			)
			(layer "F.Fab")
		)
		(fp_line
			(start 1.1938 -0.406654)
			(end 1.1938 0.4064)
			(stroke
				(width 0.1)
				(type default)
			)
			(layer "F.Fab")
		)
		(fp_line
			(start 1.1938 0.4064)
			(end 0.8636 0.4064)
			(stroke
				(width 0.1)
				(type default)
			)
			(layer "F.Fab")
		)
		(pad "1" smd rect
			(at -0.7366 0 270)
			(size 0.7112 0.8128)
			(layers "F.Cu" "F.Mask" "F.Paste")
			(net "P12V_HPDB")
		)
		(pad "2" smd rect
			(at 0.7366 0 270)
			(size 0.7112 0.8128)
			(layers "F.Cu" "F.Mask" "F.Paste")
			(net "P12V_LED_PD")
		)
	)
)
